(kicad_pcb
	(version 20260206)
	(generator "pcbnew")
	(generator_version "10.0")
	(general
		(thickness 1.6)
		(legacy_teardrops no)
	)
	(paper "A4")
	(title_block
		(title "peb — Lightning_PEB_BRD.brd")
		(comment 1 "Lightning (Wiwynn / Facebook NVMe JBOF) / footprints 1265-1270 of 2563")
	)
	(layers
		(0 "F.Cu" signal "TOP")
		(4 "In1.Cu" signal "L2GND")
		(6 "In2.Cu" signal "L3")
		(8 "In3.Cu" signal "L4VCC")
		(10 "In4.Cu" signal "L5VCC")
		(12 "In5.Cu" signal "L6")
		(14 "In6.Cu" signal "L7GND")
		(2 "B.Cu" signal "BOTTOM")
		(9 "F.Adhes" user "F.Adhesive")
		(11 "B.Adhes" user "B.Adhesive")
		(13 "F.Paste" user "Package Geometry/Pastemask Top")
		(15 "B.Paste" user "Package Geometry/Pastemask Bottom")
		(5 "F.SilkS" user "Ref Des/Silkscreen Top")
		(7 "B.SilkS" user "Ref Des/Silkscreen Bottom")
		(1 "F.Mask" user "Board Geometry/Soldermask Top")
		(3 "B.Mask" user "Board Geometry/Soldermask Bottom")
		(17 "Dwgs.User" user "User.Drawings")
		(19 "Cmts.User" user "User.Comments")
		(21 "Eco1.User" user "User.Eco1")
		(23 "Eco2.User" user "User.Eco2")
		(25 "Edge.Cuts" user "Board Geometry/Outline")
		(27 "Margin" user)
		(31 "F.CrtYd" user "Package Geometry/Place Bound Top")
		(29 "B.CrtYd" user "Package Geometry/Place Bound Bottom")
		(35 "F.Fab" user "Ref Des/Assembly Top")
		(33 "B.Fab" user "Ref Des/Assembly Bottom")
	)
	(footprint ""
		(layer "F.Cu")
		(at 310.007 -60.1726)
		(property "Reference" "PG49"
			(at 0 0 0)
			(layer "F.SilkS")
			(hide yes)
			(effects
				(font
					(size 1.27 1.27)
				)
			)
		)
		(property "Value" "GAP-CLOSE-PWR-3-GP"
			(at 0.0254 -6.5786 0)
			(unlocked yes)
			(layer "F.Fab")
			(hide yes)
			(effects
				(font
					(size 1.016 1.016)
					(thickness 0.1524)
				)
			)
		)
		(property "Device Type" "GAP-CLOSE-PWR-3"
			(at 0.0254 -8.255 0)
			(unlocked yes)
			(layer "F.Fab")
			(hide yes)
			(effects
				(font
					(size 1.016 1.016)
					(thickness 0.1524)
				)
			)
		)
		(duplicate_pad_numbers_are_jumpers no)
		(fp_rect
			(start -0.7112 0.4572)
			(end 0.7112 -0.4572)
			(stroke
				(width 0)
				(type default)
			)
			(fill no)
			(layer "F.CrtYd")
		)
		(fp_poly
			(pts
				(xy -0.7112 -0.4572) (xy 0.7112 -0.4572) (xy 0.7112 0.4572) (xy -0.7112 0.4572)
			)
			(stroke
				(width 0)
				(type default)
			)
			(fill no)
			(layer "F.Fab")
		)
		(pad "1" smd rect
			(at -0.3048 0)
			(size 0.6604 0.762)
			(layers "F.Cu" "F.Mask" "F.Paste")
			(net "DUT_VDD")
		)
		(pad "2" smd rect
			(at 0.3048 0)
			(size 0.6604 0.762)
			(layers "F.Cu" "F.Mask" "F.Paste")
			(net "P0V9_E")
		)
	)
	(footprint ""
		(layer "F.Cu")
		(at 187.231528 -0.001524 -90)
		(property "Reference" "Q21"
			(at 0 0 270)
			(layer "F.SilkS")
			(hide yes)
			(effects
				(font
					(size 1.27 1.27)
				)
			)
		)
		(property "Value" "2N7002K-1-GP"
			(at 0.127 -8.9662 270)
			(unlocked yes)
			(layer "F.Fab")
			(hide yes)
			(effects
				(font
					(size 1.016 1.016)
					(thickness 0.1524)
				)
			)
		)
		(property "Device Type" "SOT23DGS2D4H44"
			(at 0.127 -10.4902 270)
			(unlocked yes)
			(layer "F.Fab")
			(hide yes)
			(effects
				(font
					(size 1.016 1.016)
					(thickness 0.1524)
				)
			)
		)
		(duplicate_pad_numbers_are_jumpers no)
		(fp_line
			(start -1.651 1.778)
			(end 1.651 1.778)
			(stroke
				(width 0.1524)
				(type default)
			)
			(layer "F.SilkS")
		)
		(fp_line
			(start 1.651 1.778)
			(end 1.651 -1.778)
			(stroke
				(width 0.1524)
				(type default)
			)
			(layer "F.SilkS")
		)
		(fp_line
			(start -1.651 -1.778)
			(end -1.651 1.778)
			(stroke
				(width 0.1524)
				(type default)
			)
			(layer "F.SilkS")
		)
		(fp_line
			(start 1.651 -1.778)
			(end -1.651 -1.778)
			(stroke
				(width 0.1524)
				(type default)
			)
			(layer "F.SilkS")
		)
		(fp_poly
			(pts
				(xy -1.778 1.8796) (xy -1.778 -1.8796) (xy 1.778 -1.8796) (xy 1.778 1.8796)
			)
			(stroke
				(width 0)
				(type default)
			)
			(fill no)
			(layer "F.CrtYd")
		)
		(fp_poly
			(pts
				(xy -1.778 1.8796) (xy -1.778 -1.8796) (xy 1.778 -1.8796) (xy 1.778 1.8796)
			)
			(stroke
				(width 0)
				(type default)
			)
			(fill no)
			(layer "F.Fab")
		)
		(pad "D" smd custom
			(at 0 -0.9525 270)
			(size 0.1905 0.1905)
			(layers "F.Cu" "F.Mask" "F.Paste")
			(net "EXP_BMC_HB_LED_D")
			(options
				(clearance outline)
				(anchor circle)
			)
			(primitives
				(gr_poly
					(pts
						(arc
							(start -0.1778 0.5715)
							(mid -0.321484 0.511984)
							(end -0.381 0.3683)
						)
						(arc
							(start -0.381 -0.3683)
							(mid -0.321484 -0.511984)
							(end -0.1778 -0.5715)
						)
						(arc
							(start 0.1778 -0.5715)
							(mid 0.321484 -0.511984)
							(end 0.381 -0.3683)
						)
						(arc
							(start 0.381 0.3683)
							(mid 0.321484 0.511984)
							(end 0.1778 0.5715)
						)
					)
					(width 0)
					(fill yes)
				)
			)
		)
		(pad "G" smd custom
			(at -0.98425 0.9525 270)
			(size 0.1905 0.1905)
			(layers "F.Cu" "F.Mask" "F.Paste")
			(net "Q21_G")
			(options
				(clearance outline)
				(anchor circle)
			)
			(primitives
				(gr_poly
					(pts
						(arc
							(start -0.1778 0.5715)
							(mid -0.321484 0.511984)
							(end -0.381 0.3683)
						)
						(arc
							(start -0.381 -0.3683)
							(mid -0.321484 -0.511984)
							(end -0.1778 -0.5715)
						)
						(arc
							(start 0.1778 -0.5715)
							(mid 0.321484 -0.511984)
							(end 0.381 -0.3683)
						)
						(arc
							(start 0.381 0.3683)
							(mid 0.321484 0.511984)
							(end 0.1778 0.5715)
						)
					)
					(width 0)
					(fill yes)
				)
			)
		)
		(pad "S" smd custom
			(at 0.98425 0.9525 270)
			(size 0.1905 0.1905)
			(layers "F.Cu" "F.Mask" "F.Paste")
			(net "GND")
			(options
				(clearance outline)
				(anchor circle)
			)
			(primitives
				(gr_poly
					(pts
						(arc
							(start -0.1778 0.5715)
							(mid -0.321484 0.511984)
							(end -0.381 0.3683)
						)
						(arc
							(start -0.381 -0.3683)
							(mid -0.321484 -0.511984)
							(end -0.1778 -0.5715)
						)
						(arc
							(start 0.1778 -0.5715)
							(mid 0.321484 -0.511984)
							(end 0.381 -0.3683)
						)
						(arc
							(start 0.381 0.3683)
							(mid 0.321484 0.511984)
							(end 0.1778 0.5715)
						)
					)
					(width 0)
					(fill yes)
				)
			)
		)
	)
	(footprint ""
		(layer "F.Cu")
		(at 194.8688 -32.8676 90)
		(property "Reference" "R778"
			(at 0 0 90)
			(layer "F.SilkS")
			(hide yes)
			(effects
				(font
					(size 1.27 1.27)
				)
			)
		)
		(property "Value" "4K7R2F-GP"
			(at 0.064008 -3.993896 90)
			(unlocked yes)
			(layer "F.Fab")
			(hide yes)
			(effects
				(font
					(size 1.016 1.016)
					(thickness 0.1524)
				)
			)
		)
		(property "Device Type" "R402H16"
			(at 0.064008 -5.517896 90)
			(unlocked yes)
			(layer "F.Fab")
			(hide yes)
			(effects
				(font
					(size 1.016 1.016)
					(thickness 0.1524)
				)
			)
		)
		(duplicate_pad_numbers_are_jumpers no)
		(fp_line
			(start 0.508 -0.9398)
			(end -0.508 -0.9398)
			(stroke
				(width 0.1524)
				(type default)
			)
			(layer "F.SilkS")
		)
		(fp_line
			(start -0.508 -0.9398)
			(end -0.508 0.9398)
			(stroke
				(width 0.1524)
				(type default)
			)
			(layer "F.SilkS")
		)
		(fp_rect
			(start -0.508 0.9398)
			(end 0.508 -0.9398)
			(stroke
				(width 0)
				(type default)
			)
			(fill no)
			(layer "F.CrtYd")
		)
		(fp_rect
			(start -0.508 0.9398)
			(end 0.508 -0.9398)
			(stroke
				(width 0)
				(type default)
			)
			(fill no)
			(layer "F.Fab")
		)
		(pad "1" smd custom
			(at 0 -0.4445 90)
			(size 0.1397 0.1397)
			(layers "F.Cu" "F.Mask" "F.Paste")
			(net "GND")
			(options
				(clearance outline)
				(anchor circle)
			)
			(primitives
				(gr_poly
					(pts
						(arc
							(start -0.1778 -0.2794)
							(mid -0.249642 -0.249642)
							(end -0.2794 -0.1778)
						)
						(arc
							(start -0.2794 0.1778)
							(mid -0.249642 0.249642)
							(end -0.1778 0.2794)
						)
						(arc
							(start 0.1778 0.2794)
							(mid 0.249642 0.249642)
							(end 0.2794 0.1778)
						)
						(arc
							(start 0.2794 -0.1778)
							(mid 0.249642 -0.249642)
							(end 0.1778 -0.2794)
						)
					)
					(width 0)
					(fill yes)
				)
			)
		)
		(pad "2" smd custom
			(at 0 0.4445 90)
			(size 0.1397 0.1397)
			(layers "F.Cu" "F.Mask" "F.Paste")
			(net "U55_A1")
			(options
				(clearance outline)
				(anchor circle)
			)
			(primitives
				(gr_poly
					(pts
						(arc
							(start -0.1778 -0.2794)
							(mid -0.249642 -0.249642)
							(end -0.2794 -0.1778)
						)
						(arc
							(start -0.2794 0.1778)
							(mid -0.249642 0.249642)
							(end -0.1778 0.2794)
						)
						(arc
							(start 0.1778 0.2794)
							(mid 0.249642 0.249642)
							(end 0.2794 0.1778)
						)
						(arc
							(start 0.2794 -0.1778)
							(mid 0.249642 -0.249642)
							(end 0.1778 -0.2794)
						)
					)
					(width 0)
					(fill yes)
				)
			)
		)
	)
	(footprint ""
		(layer "F.Cu")
		(at 208.099914 -69.939916 -90)
		(property "Reference" "CN7"
			(at 0 0 270)
			(layer "F.SilkS")
			(hide yes)
			(effects
				(font
					(size 1.27 1.27)
				)
			)
		)
		(property "Value" "FOX-CON2-S23-GP"
			(at 5.334 1.4478 270)
			(unlocked yes)
			(layer "F.Fab")
			(hide yes)
			(effects
				(font
					(size 1.016 1.016)
					(thickness 0.1524)
				)
			)
		)
		(property "Device Type" "HBA1030-H300R-EF"
			(at 5.334 -0.0762 270)
			(unlocked yes)
			(layer "F.Fab")
			(hide yes)
			(effects
				(font
					(size 1.016 1.016)
					(thickness 0.1524)
				)
			)
		)
		(duplicate_pad_numbers_are_jumpers no)
		(fp_line
			(start -3.937 1.4859)
			(end -3.937 -1.4859)
			(stroke
				(width 0.1524)
				(type default)
			)
			(layer "F.SilkS")
		)
		(fp_line
			(start 3.937 1.4859)
			(end -3.937 1.4859)
			(stroke
				(width 0.1524)
				(type default)
			)
			(layer "F.SilkS")
		)
		(fp_line
			(start -4.082288 -0.36576)
			(end -4.082288 -1.63576)
			(stroke
				(width 0.4064)
				(type default)
			)
			(layer "F.SilkS")
		)
		(fp_line
			(start -3.937 -1.4859)
			(end 3.937 -1.4859)
			(stroke
				(width 0.1524)
				(type default)
			)
			(layer "F.SilkS")
		)
		(fp_line
			(start 3.937 -1.4859)
			(end 3.937 1.4859)
			(stroke
				(width 0.1524)
				(type default)
			)
			(layer "F.SilkS")
		)
		(fp_line
			(start -4.082288 -1.63576)
			(end -2.812288 -1.63576)
			(stroke
				(width 0.4064)
				(type default)
			)
			(layer "F.SilkS")
		)
		(fp_circle
			(center -2.54 0)
			(end -2.54 -1.0668)
			(stroke
				(width 0.3048)
				(type default)
			)
			(fill no)
			(layer "F.SilkS")
		)
		(fp_circle
			(center 2.54 0)
			(end 2.54 -1.0668)
			(stroke
				(width 0.3048)
				(type default)
			)
			(fill no)
			(layer "F.SilkS")
		)
		(fp_rect
			(start -3.683 1.2319)
			(end 3.683 -1.2319)
			(stroke
				(width 0)
				(type default)
			)
			(fill no)
			(layer "F.CrtYd")
		)
		(fp_poly
			(pts
				(xy -4.191 1.7399) (xy -4.191 -1.7399) (xy 4.191 -1.7399) (xy 4.191 1.7399) (xy -0.2413 1.7399)
				(xy -0.2413 1.2319) (xy 3.683 1.2319) (xy 3.683 -1.2319) (xy -3.683 -1.2319) (xy -3.683 1.2319)
				(xy -0.254 1.2319) (xy -0.254 1.7399)
			)
			(stroke
				(width 0)
				(type default)
			)
			(fill no)
			(layer "F.CrtYd")
		)
		(fp_rect
			(start -4.191 1.7399)
			(end 4.191 -1.7399)
			(stroke
				(width 0)
				(type default)
			)
			(fill no)
			(layer "F.Fab")
		)
		(pad "1" thru_hole circle
			(at -2.54 0 270)
			(size 1.4224 1.4224)
			(drill 1.016)
			(layers "*.Cu" "*.Mask")
			(remove_unused_layers no)
			(net "GND")
			(clearance 0.1524)
			(thermal_gap 0.1524)
		)
		(pad "2" thru_hole circle
			(at 2.54 0 270)
			(size 1.4224 1.4224)
			(drill 1.016)
			(layers "*.Cu" "*.Mask")
			(remove_unused_layers no)
			(net "GND")
			(clearance 0.1524)
			(thermal_gap 0.1524)
		)
	)
	(footprint ""
		(layer "F.Cu")
		(at 20.3962 -66.2686)
		(property "Reference" "R419"
			(at 0 0 0)
			(layer "F.SilkS")
			(hide yes)
			(effects
				(font
					(size 1.27 1.27)
				)
			)
		)
		(property "Value" "10KR2F-2-GP"
			(at 0.064008 -3.993896 0)
			(unlocked yes)
			(layer "F.Fab")
			(hide yes)
			(effects
				(font
					(size 1.016 1.016)
					(thickness 0.1524)
				)
			)
		)
		(property "Device Type" "R402H16"
			(at 0.064008 -5.517896 0)
			(unlocked yes)
			(layer "F.Fab")
			(hide yes)
			(effects
				(font
					(size 1.016 1.016)
					(thickness 0.1524)
				)
			)
		)
		(duplicate_pad_numbers_are_jumpers no)
		(fp_line
			(start -0.508 -0.9398)
			(end -0.508 0.9398)
			(stroke
				(width 0.1524)
				(type default)
			)
			(layer "F.SilkS")
		)
		(fp_line
			(start 0.508 -0.9398)
			(end -0.508 -0.9398)
			(stroke
				(width 0.1524)
				(type default)
			)
			(layer "F.SilkS")
		)
		(fp_rect
			(start -0.508 0.9398)
			(end 0.508 -0.9398)
			(stroke
				(width 0)
				(type default)
			)
			(fill no)
			(layer "F.CrtYd")
		)
		(fp_rect
			(start -0.508 0.9398)
			(end 0.508 -0.9398)
			(stroke
				(width 0)
				(type default)
			)
			(fill no)
			(layer "F.Fab")
		)
		(pad "1" smd custom
			(at 0 -0.4445)
			(size 0.1397 0.1397)
			(layers "F.Cu" "F.Mask" "F.Paste")
			(net "PCIE_DIS")
			(options
				(clearance outline)
				(anchor circle)
			)
			(primitives
				(gr_poly
					(pts
						(arc
							(start -0.1778 -0.2794)
							(mid -0.249642 -0.249642)
							(end -0.2794 -0.1778)
						)
						(arc
							(start -0.2794 0.1778)
							(mid -0.249642 0.249642)
							(end -0.1778 0.2794)
						)
						(arc
							(start 0.1778 0.2794)
							(mid 0.249642 0.249642)
							(end 0.2794 0.1778)
						)
						(arc
							(start 0.2794 -0.1778)
							(mid 0.249642 -0.249642)
							(end 0.1778 -0.2794)
						)
					)
					(width 0)
					(fill yes)
				)
			)
		)
		(pad "2" smd custom
			(at 0 0.4445)
			(size 0.1397 0.1397)
			(layers "F.Cu" "F.Mask" "F.Paste")
			(net "P3V3_STBY")
			(options
				(clearance outline)
				(anchor circle)
			)
			(primitives
				(gr_poly
					(pts
						(arc
							(start -0.1778 -0.2794)
							(mid -0.249642 -0.249642)
							(end -0.2794 -0.1778)
						)
						(arc
							(start -0.2794 0.1778)
							(mid -0.249642 0.249642)
							(end -0.1778 0.2794)
						)
						(arc
							(start 0.1778 0.2794)
							(mid 0.249642 0.249642)
							(end 0.2794 0.1778)
						)
						(arc
							(start 0.2794 -0.1778)
							(mid 0.249642 -0.249642)
							(end 0.1778 -0.2794)
						)
					)
					(width 0)
					(fill yes)
				)
			)
		)
	)
	(footprint ""
		(layer "F.Cu")
		(at 217.007948 -212.420454 180)
		(property "Reference" "C108"
			(at 0 0 180)
			(layer "F.SilkS")
			(hide yes)
			(effects
				(font
					(size 1.27 1.27)
				)
			)
		)
		(property "Value" "SCD22U10V2KX-1GP"
			(at 1.1811 -2.7051 180)
			(unlocked yes)
			(layer "F.Fab")
			(hide yes)
			(effects
				(font
					(size 1.016 1.016)
					(thickness 0.1524)
				)
			)
		)
		(property "Device Type" "C402H22"
			(at 1.1811 -4.2291 180)
			(unlocked yes)
			(layer "F.Fab")
			(hide yes)
			(effects
				(font
					(size 1.016 1.016)
					(thickness 0.1524)
				)
			)
		)
		(duplicate_pad_numbers_are_jumpers no)
		(fp_rect
			(start -0.4318 0.9525)
			(end 0.4318 -0.9525)
			(stroke
				(width 0)
				(type default)
			)
			(fill no)
			(layer "F.CrtYd")
		)
		(fp_rect
			(start -0.4318 0.9525)
			(end 0.4318 -0.9525)
			(stroke
				(width 0)
				(type default)
			)
			(fill no)
			(layer "F.Fab")
		)
		(pad "1" smd custom
			(at 0 -0.4445 180)
			(size 0.1524 0.1524)
			(layers "F.Cu" "F.Mask" "F.Paste")
			(net "PCIE_TX_CAP_N38")
			(options
				(clearance outline)
				(anchor circle)
			)
			(primitives
				(gr_poly
					(pts
						(arc
							(start 0.3048 -0.2032)
							(mid 0.275042 -0.275042)
							(end 0.2032 -0.3048)
						)
						(arc
							(start -0.2032 -0.3048)
							(mid -0.275042 -0.275042)
							(end -0.3048 -0.2032)
						)
						(arc
							(start -0.3048 0.2032)
							(mid -0.275042 0.275042)
							(end -0.2032 0.3048)
						)
						(arc
							(start 0.2032 0.3048)
							(mid 0.275042 0.275042)
							(end 0.3048 0.2032)
						)
					)
					(width 0)
					(fill yes)
				)
			)
		)
		(pad "2" smd custom
			(at 0 0.4445 180)
			(size 0.1524 0.1524)
			(layers "F.Cu" "F.Mask" "F.Paste")
			(net "PCIE_TX_N38")
			(options
				(clearance outline)
				(anchor circle)
			)
			(primitives
				(gr_poly
					(pts
						(arc
							(start 0.3048 -0.2032)
							(mid 0.275042 -0.275042)
							(end 0.2032 -0.3048)
						)
						(arc
							(start -0.2032 -0.3048)
							(mid -0.275042 -0.275042)
							(end -0.3048 -0.2032)
						)
						(arc
							(start -0.3048 0.2032)
							(mid -0.275042 0.275042)
							(end -0.2032 0.3048)
						)
						(arc
							(start 0.2032 0.3048)
							(mid 0.275042 0.275042)
							(end 0.3048 0.2032)
						)
					)
					(width 0)
					(fill yes)
				)
			)
		)
	)
)
